# T6G (Grand Teton) — schematic netlist excerpt (pin names and nets, part order shuffled) for the footprints in the layout excerpt that follows; sources: Cadence DE-HDL packaged netlist, KiCad conversion of 04192023_DAF0TMB3IC0_F0TG_MB_C_brd_V02_OCP.brd

R282  Q_RES  33 5% CHIP  pkg 0402LF  page 81 : A = PVDDIO_P1_EN ; B = FM_PVDDIO_P1_EN
C711  Q_CAP_DIFFBUS  DIFF BUS_0.22UF 6.3V 20% X6S  pkg C0201  page 66 : \1\ = P5E_CPU1_P1_TX_C_DP<15> ; \2\ = P5E_CPU1_P1_TX_DP<15>
R6025  Q_RES  0 5% CHIP  pkg 0402LF  page 150 : A = SGPIO_SCM_RESET_N ; B = SGPIO_SCM_RESET_R_N

(kicad_pcb
	(version 20260206)
	(generator "pcbnew")
	(generator_version "10.0")
	(general
		(thickness 1.6)
		(legacy_teardrops no)
	)
	(paper "A4")
	(title_block
		(title "04192023_DAF0TMB3IC0_F0TG_MB_C_brd_V02_OCP.brd")
		(comment 1 "Grand Teton / footprints 4509-4511 of 8354")
	)
	(layers
		(0 "F.Cu" signal "TOP")
		(4 "In1.Cu" signal "GND")
		(6 "In2.Cu" signal "IN1")
		(8 "In3.Cu" signal "GND1")
		(10 "In4.Cu" signal "IN2")
		(12 "In5.Cu" signal "GND2")
		(14 "In6.Cu" signal "IN3")
		(16 "In7.Cu" signal "GND3")
		(18 "In8.Cu" signal "VCC")
		(20 "In9.Cu" signal "VCC1")
		(22 "In10.Cu" signal "GND4")
		(24 "In11.Cu" signal "IN4")
		(26 "In12.Cu" signal "GND5")
		(28 "In13.Cu" signal "IN5")
		(30 "In14.Cu" signal "GND6")
		(32 "In15.Cu" signal "IN6")
		(34 "In16.Cu" signal "GND7")
		(2 "B.Cu" signal "BOTTOM")
		(9 "F.Adhes" user "F.Adhesive")
		(11 "B.Adhes" user "B.Adhesive")
		(13 "F.Paste" user "Package Geometry/Pastemask Top")
		(15 "B.Paste" user "Package Geometry/Pastemask Bottom")
		(5 "F.SilkS" user "Ref Des/Silkscreen Top")
		(7 "B.SilkS" user "Ref Des/Silkscreen Bottom")
		(1 "F.Mask" user "Board Geometry/Soldermask Top")
		(3 "B.Mask" user "Board Geometry/Soldermask Bottom")
		(17 "Dwgs.User" user "User.Drawings")
		(19 "Cmts.User" user "User.Comments")
		(21 "Eco1.User" user "User.Eco1")
		(23 "Eco2.User" user "User.Eco2")
		(25 "Edge.Cuts" user "Board Geometry/Outline")
		(27 "Margin" user)
		(31 "F.CrtYd" user "Package Geometry/Place Bound Top")
		(29 "B.CrtYd" user "Package Geometry/Place Bound Bottom")
		(35 "F.Fab" user "Ref Des/Assembly Top")
		(33 "B.Fab" user "Ref Des/Assembly Bottom")
	)
	(footprint ""
		(layer "F.Cu")
		(at 170.8912 -94.833948 -90)
		(property "Reference" "R6025"
			(at 0 0 270)
			(layer "F.SilkS")
			(hide yes)
			(effects
				(font
					(size 1.27 1.27)
				)
			)
		)
		(property "Value" ""
			(at 0 0 270)
			(layer "F.Fab")
			(effects
				(font
					(size 1.27 1.27)
				)
			)
		)
		(duplicate_pad_numbers_are_jumpers no)
		(fp_line
			(start -0.7874 0.4064)
			(end -0.7874 -0.4064)
			(stroke
				(width 0.1524)
				(type default)
			)
			(layer "F.SilkS")
		)
		(fp_line
			(start 0.7874 0.4064)
			(end -0.7874 0.4064)
			(stroke
				(width 0.1524)
				(type default)
			)
			(layer "F.SilkS")
		)
		(fp_line
			(start -0.7874 -0.4064)
			(end 0.7874 -0.4064)
			(stroke
				(width 0.1524)
				(type default)
			)
			(layer "F.SilkS")
		)
		(fp_line
			(start 0.7874 -0.4064)
			(end 0.7874 0.4064)
			(stroke
				(width 0.1524)
				(type default)
			)
			(layer "F.SilkS")
		)
		(fp_line
			(start -0.67945 0.3048)
			(end -0.67945 -0.305054)
			(stroke
				(width 0.1)
				(type default)
			)
			(layer "F.Fab")
		)
		(fp_line
			(start -0.12065 0.3048)
			(end -0.67945 0.3048)
			(stroke
				(width 0.1)
				(type default)
			)
			(layer "F.Fab")
		)
		(fp_line
			(start 0.120396 0.3048)
			(end 0.120396 0.2794)
			(stroke
				(width 0.1)
				(type default)
			)
			(layer "F.Fab")
		)
		(fp_line
			(start 0.67945 0.3048)
			(end 0.120396 0.3048)
			(stroke
				(width 0.1)
				(type default)
			)
			(layer "F.Fab")
		)
		(fp_line
			(start -0.12065 0.2794)
			(end -0.12065 0.3048)
			(stroke
				(width 0.1)
				(type default)
			)
			(layer "F.Fab")
		)
		(fp_line
			(start 0.120396 0.2794)
			(end -0.12065 0.2794)
			(stroke
				(width 0.1)
				(type default)
			)
			(layer "F.Fab")
		)
		(fp_line
			(start -0.12065 -0.2794)
			(end 0.12065 -0.2794)
			(stroke
				(width 0.1)
				(type default)
			)
			(layer "F.Fab")
		)
		(fp_line
			(start 0.12065 -0.2794)
			(end 0.12065 -0.3048)
			(stroke
				(width 0.1)
				(type default)
			)
			(layer "F.Fab")
		)
		(fp_line
			(start 0.12065 -0.3048)
			(end 0.67945 -0.3048)
			(stroke
				(width 0.1)
				(type default)
			)
			(layer "F.Fab")
		)
		(fp_line
			(start 0.67945 -0.3048)
			(end 0.67945 0.3048)
			(stroke
				(width 0.1)
				(type default)
			)
			(layer "F.Fab")
		)
		(fp_line
			(start -0.67945 -0.305054)
			(end -0.12065 -0.305054)
			(stroke
				(width 0.1)
				(type default)
			)
			(layer "F.Fab")
		)
		(fp_line
			(start -0.12065 -0.305054)
			(end -0.12065 -0.2794)
			(stroke
				(width 0.1)
				(type default)
			)
			(layer "F.Fab")
		)
		(pad "1" smd circle
			(at -0.40005 0 270)
			(size 0 0)
			(layers "F.Cu" "F.Mask" "F.Paste")
			(net "SGPIO_SCM_RESET_N")
		)
		(pad "2" smd circle
			(at 0.40005 0 270)
			(size 0 0)
			(layers "F.Cu" "F.Mask" "F.Paste")
			(net "SGPIO_SCM_RESET_R_N")
		)
	)
	(footprint ""
		(layer "F.Cu")
		(at 102.268782 -379.471428)
		(property "Reference" "C711"
			(at 0 0 0)
			(layer "F.SilkS")
			(hide yes)
			(effects
				(font
					(size 1.27 1.27)
				)
			)
		)
		(property "Value" ""
			(at 0 0 0)
			(layer "F.Fab")
			(effects
				(font
					(size 1.27 1.27)
				)
			)
		)
		(duplicate_pad_numbers_are_jumpers no)
		(fp_line
			(start -0.299974 -0.150114)
			(end 0.299974 -0.150114)
			(stroke
				(width 0.1)
				(type default)
			)
			(layer "F.Fab")
		)
		(fp_line
			(start -0.299974 0.150114)
			(end -0.299974 -0.150114)
			(stroke
				(width 0.1)
				(type default)
			)
			(layer "F.Fab")
		)
		(fp_line
			(start 0.299974 -0.150114)
			(end 0.299974 0.150114)
			(stroke
				(width 0.1)
				(type default)
			)
			(layer "F.Fab")
		)
		(fp_line
			(start 0.299974 0.150114)
			(end -0.299974 0.150114)
			(stroke
				(width 0.1)
				(type default)
			)
			(layer "F.Fab")
		)
		(pad "1" smd rect
			(at -0.2667 0)
			(size 0.3048 0.381)
			(layers "F.Cu" "F.Mask" "F.Paste")
			(net "P5E_CPU1_P1_TX_C_DP<15>")
		)
		(pad "2" smd rect
			(at 0.2667 0)
			(size 0.3048 0.381)
			(layers "F.Cu" "F.Mask" "F.Paste")
			(net "P5E_CPU1_P1_TX_DP<15>")
		)
	)
	(footprint ""
		(layer "F.Cu")
		(at 197.269608 -112.609376 180)
		(property "Reference" "R282"
			(at 0 0 180)
			(layer "F.SilkS")
			(hide yes)
			(effects
				(font
					(size 1.27 1.27)
				)
			)
		)
		(property "Value" ""
			(at 0 0 180)
			(layer "F.Fab")
			(effects
				(font
					(size 1.27 1.27)
				)
			)
		)
		(duplicate_pad_numbers_are_jumpers no)
		(fp_line
			(start 0.7874 0.4064)
			(end -0.7874 0.4064)
			(stroke
				(width 0.1524)
				(type default)
			)
			(layer "F.SilkS")
		)
		(fp_line
			(start 0.7874 -0.4064)
			(end 0.7874 0.4064)
			(stroke
				(width 0.1524)
				(type default)
			)
			(layer "F.SilkS")
		)
		(fp_line
			(start -0.7874 0.4064)
			(end -0.7874 -0.4064)
			(stroke
				(width 0.1524)
				(type default)
			)
			(layer "F.SilkS")
		)
		(fp_line
			(start -0.7874 -0.4064)
			(end 0.7874 -0.4064)
			(stroke
				(width 0.1524)
				(type default)
			)
			(layer "F.SilkS")
		)
		(fp_line
			(start 0.67945 0.3048)
			(end 0.120396 0.3048)
			(stroke
				(width 0.1)
				(type default)
			)
			(layer "F.Fab")
		)
		(fp_line
			(start 0.67945 -0.3048)
			(end 0.67945 0.3048)
			(stroke
				(width 0.1)
				(type default)
			)
			(layer "F.Fab")
		)
		(fp_line
			(start 0.12065 -0.2794)
			(end 0.12065 -0.3048)
			(stroke
				(width 0.1)
				(type default)
			)
			(layer "F.Fab")
		)
		(fp_line
			(start 0.12065 -0.3048)
			(end 0.67945 -0.3048)
			(stroke
				(width 0.1)
				(type default)
			)
			(layer "F.Fab")
		)
		(fp_line
			(start 0.120396 0.3048)
			(end 0.120396 0.2794)
			(stroke
				(width 0.1)
				(type default)
			)
			(layer "F.Fab")
		)
		(fp_line
			(start 0.120396 0.2794)
			(end -0.12065 0.2794)
			(stroke
				(width 0.1)
				(type default)
			)
			(layer "F.Fab")
		)
		(fp_line
			(start -0.12065 0.3048)
			(end -0.67945 0.3048)
			(stroke
				(width 0.1)
				(type default)
			)
			(layer "F.Fab")
		)
		(fp_line
			(start -0.12065 0.2794)
			(end -0.12065 0.3048)
			(stroke
				(width 0.1)
				(type default)
			)
			(layer "F.Fab")
		)
		(fp_line
			(start -0.12065 -0.2794)
			(end 0.12065 -0.2794)
			(stroke
				(width 0.1)
				(type default)
			)
			(layer "F.Fab")
		)
		(fp_line
			(start -0.12065 -0.305054)
			(end -0.12065 -0.2794)
			(stroke
				(width 0.1)
				(type default)
			)
			(layer "F.Fab")
		)
		(fp_line
			(start -0.67945 0.3048)
			(end -0.67945 -0.305054)
			(stroke
				(width 0.1)
				(type default)
			)
			(layer "F.Fab")
		)
		(fp_line
			(start -0.67945 -0.305054)
			(end -0.12065 -0.305054)
			(stroke
				(width 0.1)
				(type default)
			)
			(layer "F.Fab")
		)
		(pad "1" smd circle
			(at -0.40005 0 180)
			(size 0 0)
			(layers "F.Cu" "F.Mask" "F.Paste")
			(net "PVDDIO_P1_EN")
		)
		(pad "2" smd circle
			(at 0.40005 0 180)
			(size 0 0)
			(layers "F.Cu" "F.Mask" "F.Paste")
			(net "FM_PVDDIO_P1_EN")
		)
	)
)
